(kicad_pcb
	(version 20260206)
	(generator "pcbnew")
	(generator_version "10.0")
	(general
		(thickness 1.6)
		(legacy_teardrops no)
	)
	(paper "A4")
	(title_block
		(title "Bryce Canyon_R.DPB_16317-1_OCP.brd")
		(comment 1 "Bryce Canyon / footprints 1900-1906 of 2099")
	)
	(layers
		(0 "F.Cu" signal "TOP")
		(4 "In1.Cu" signal "L2GND")
		(6 "In2.Cu" signal "L3")
		(8 "In3.Cu" signal "L4VCC")
		(10 "In4.Cu" signal "L5VCC")
		(12 "In5.Cu" signal "L6")
		(14 "In6.Cu" signal "L7GND")
		(2 "B.Cu" signal "BOTTOM")
		(9 "F.Adhes" user "F.Adhesive")
		(11 "B.Adhes" user "B.Adhesive")
		(13 "F.Paste" user "Package Geometry/Pastemask Top")
		(15 "B.Paste" user "Package Geometry/Pastemask Bottom")
		(5 "F.SilkS" user "Ref Des/Silkscreen Top")
		(7 "B.SilkS" user "Ref Des/Silkscreen Bottom")
		(1 "F.Mask" user "Board Geometry/Soldermask Top")
		(3 "B.Mask" user "Board Geometry/Soldermask Bottom")
		(17 "Dwgs.User" user "User.Drawings")
		(19 "Cmts.User" user "User.Comments")
		(21 "Eco1.User" user "User.Eco1")
		(23 "Eco2.User" user "User.Eco2")
		(25 "Edge.Cuts" user "Board Geometry/Outline")
		(27 "Margin" user)
		(31 "F.CrtYd" user "Package Geometry/Place Bound Top")
		(29 "B.CrtYd" user "Package Geometry/Place Bound Bottom")
		(35 "F.Fab" user "Ref Des/Assembly Top")
		(33 "B.Fab" user "Ref Des/Assembly Bottom")
	)
	(footprint ""
		(layer "F.Cu")
		(at 261.117334 -211.051902 90)
		(property "Reference" "R1295"
			(at 0 0 90)
			(layer "F.SilkS")
			(hide yes)
			(effects
				(font
					(size 1.27 1.27)
				)
			)
		)
		(property "Value" "1KR2J-1-GP"
			(at 0.064008 -3.993896 90)
			(unlocked yes)
			(layer "F.Fab")
			(hide yes)
			(effects
				(font
					(size 1.016 1.016)
					(thickness 0.1524)
				)
			)
		)
		(property "Device Type" "R402H16"
			(at 0.064008 -5.517896 90)
			(unlocked yes)
			(layer "F.Fab")
			(hide yes)
			(effects
				(font
					(size 1.016 1.016)
					(thickness 0.1524)
				)
			)
		)
		(duplicate_pad_numbers_are_jumpers no)
		(fp_line
			(start 0.508 -0.9398)
			(end -0.508 -0.9398)
			(stroke
				(width 0.1524)
				(type default)
			)
			(layer "F.SilkS")
		)
		(fp_line
			(start -0.508 -0.9398)
			(end -0.508 0.9398)
			(stroke
				(width 0.1524)
				(type default)
			)
			(layer "F.SilkS")
		)
		(fp_rect
			(start -0.508 0.9398)
			(end 0.508 -0.9398)
			(stroke
				(width 0)
				(type default)
			)
			(fill no)
			(layer "F.CrtYd")
		)
		(fp_rect
			(start -0.508 0.9398)
			(end 0.508 -0.9398)
			(stroke
				(width 0)
				(type default)
			)
			(fill no)
			(layer "F.Fab")
		)
		(pad "1" smd custom
			(at 0 -0.4445 90)
			(size 0.1397 0.1397)
			(layers "F.Cu" "F.Mask" "F.Paste")
			(net "P3V3_STBY_B")
			(options
				(clearance outline)
				(anchor circle)
			)
			(primitives
				(gr_poly
					(pts
						(arc
							(start -0.1778 -0.2794)
							(mid -0.249642 -0.249642)
							(end -0.2794 -0.1778)
						)
						(arc
							(start -0.2794 0.1778)
							(mid -0.249642 0.249642)
							(end -0.1778 0.2794)
						)
						(arc
							(start 0.1778 0.2794)
							(mid 0.249642 0.249642)
							(end 0.2794 0.1778)
						)
						(arc
							(start 0.2794 -0.1778)
							(mid 0.249642 -0.249642)
							(end 0.1778 -0.2794)
						)
					)
					(width 0)
					(fill yes)
				)
			)
		)
		(pad "2" smd custom
			(at 0 0.4445 90)
			(size 0.1397 0.1397)
			(layers "F.Cu" "F.Mask" "F.Paste")
			(net "I2C_DRIVE_B_PWR_SDA")
			(options
				(clearance outline)
				(anchor circle)
			)
			(primitives
				(gr_poly
					(pts
						(arc
							(start -0.1778 -0.2794)
							(mid -0.249642 -0.249642)
							(end -0.2794 -0.1778)
						)
						(arc
							(start -0.2794 0.1778)
							(mid -0.249642 0.249642)
							(end -0.1778 0.2794)
						)
						(arc
							(start 0.1778 0.2794)
							(mid 0.249642 0.249642)
							(end 0.2794 0.1778)
						)
						(arc
							(start 0.2794 -0.1778)
							(mid 0.249642 -0.249642)
							(end 0.1778 -0.2794)
						)
					)
					(width 0)
					(fill yes)
				)
			)
		)
	)
	(footprint ""
		(layer "F.Cu")
		(at 180.975 -369.189 -90)
		(property "Reference" "R992"
			(at 0 0 270)
			(layer "F.SilkS")
			(hide yes)
			(effects
				(font
					(size 1.27 1.27)
				)
			)
		)
		(property "Value" "0R2J-2-GP"
			(at 0.064008 -3.993896 270)
			(unlocked yes)
			(layer "F.Fab")
			(hide yes)
			(effects
				(font
					(size 1.016 1.016)
					(thickness 0.1524)
				)
			)
		)
		(property "Device Type" "R402H16"
			(at 0.064008 -5.517896 270)
			(unlocked yes)
			(layer "F.Fab")
			(hide yes)
			(effects
				(font
					(size 1.016 1.016)
					(thickness 0.1524)
				)
			)
		)
		(duplicate_pad_numbers_are_jumpers no)
		(fp_line
			(start -0.508 -0.9398)
			(end -0.508 0.9398)
			(stroke
				(width 0.1524)
				(type default)
			)
			(layer "F.SilkS")
		)
		(fp_line
			(start 0.508 -0.9398)
			(end -0.508 -0.9398)
			(stroke
				(width 0.1524)
				(type default)
			)
			(layer "F.SilkS")
		)
		(fp_rect
			(start -0.508 0.9398)
			(end 0.508 -0.9398)
			(stroke
				(width 0)
				(type default)
			)
			(fill no)
			(layer "F.CrtYd")
		)
		(fp_rect
			(start -0.508 0.9398)
			(end 0.508 -0.9398)
			(stroke
				(width 0)
				(type default)
			)
			(fill no)
			(layer "F.Fab")
		)
		(pad "1" smd custom
			(at 0 -0.4445 270)
			(size 0.1397 0.1397)
			(layers "F.Cu" "F.Mask" "F.Paste")
			(net "12V_HS_ENABLE")
			(options
				(clearance outline)
				(anchor circle)
			)
			(primitives
				(gr_poly
					(pts
						(arc
							(start -0.1778 -0.2794)
							(mid -0.249642 -0.249642)
							(end -0.2794 -0.1778)
						)
						(arc
							(start -0.2794 0.1778)
							(mid -0.249642 0.249642)
							(end -0.1778 0.2794)
						)
						(arc
							(start 0.1778 0.2794)
							(mid 0.249642 0.249642)
							(end 0.2794 0.1778)
						)
						(arc
							(start 0.2794 -0.1778)
							(mid 0.249642 -0.249642)
							(end 0.1778 -0.2794)
						)
					)
					(width 0)
					(fill yes)
				)
			)
		)
		(pad "2" smd custom
			(at 0 0.4445 270)
			(size 0.1397 0.1397)
			(layers "F.Cu" "F.Mask" "F.Paste")
			(net "MB0_HS_ENABLE")
			(options
				(clearance outline)
				(anchor circle)
			)
			(primitives
				(gr_poly
					(pts
						(arc
							(start -0.1778 -0.2794)
							(mid -0.249642 -0.249642)
							(end -0.2794 -0.1778)
						)
						(arc
							(start -0.2794 0.1778)
							(mid -0.249642 0.249642)
							(end -0.1778 0.2794)
						)
						(arc
							(start 0.1778 0.2794)
							(mid 0.249642 0.249642)
							(end 0.2794 0.1778)
						)
						(arc
							(start 0.2794 -0.1778)
							(mid 0.249642 -0.249642)
							(end 0.1778 -0.2794)
						)
					)
					(width 0)
					(fill yes)
				)
			)
		)
	)
	(footprint ""
		(layer "F.Cu")
		(at 469.9 -260.858)
		(property "Reference" "Q44"
			(at 0 0 0)
			(layer "F.SilkS")
			(hide yes)
			(effects
				(font
					(size 1.27 1.27)
				)
			)
		)
		(property "Value" "AO4407AL-GP"
			(at -3.707384 -1.5367 0)
			(unlocked yes)
			(layer "F.Fab")
			(hide yes)
			(effects
				(font
					(size 1.016 1.016)
					(thickness 0.1524)
				)
			)
		)
		(property "Device Type" "SOIC8H69"
			(at -3.707384 -3.0607 0)
			(unlocked yes)
			(layer "F.Fab")
			(hide yes)
			(effects
				(font
					(size 1.016 1.016)
					(thickness 0.1524)
				)
			)
		)
		(duplicate_pad_numbers_are_jumpers no)
		(fp_line
			(start -2.7432 -1.4224)
			(end -2.7432 1.4224)
			(stroke
				(width 0.1524)
				(type default)
			)
			(layer "F.SilkS")
		)
		(fp_line
			(start -2.7432 1.4224)
			(end -2.6416 1.4224)
			(stroke
				(width 0.1524)
				(type default)
			)
			(layer "F.SilkS")
		)
		(fp_line
			(start -2.7432 1.4224)
			(end 2.1336 1.4224)
			(stroke
				(width 0.1524)
				(type default)
			)
			(layer "F.SilkS")
		)
		(fp_line
			(start -2.7178 -0.508)
			(end -2.1844 -0.0508)
			(stroke
				(width 0.1524)
				(type default)
			)
			(layer "F.SilkS")
		)
		(fp_line
			(start -2.6289 3.4417)
			(end -2.6289 1.4732)
			(stroke
				(width 0.381)
				(type default)
			)
			(layer "F.SilkS")
		)
		(fp_line
			(start -2.1844 -0.0508)
			(end -2.7178 0.508)
			(stroke
				(width 0.1524)
				(type default)
			)
			(layer "F.SilkS")
		)
		(fp_line
			(start 2.1336 -1.4224)
			(end -2.7432 -1.4224)
			(stroke
				(width 0.1524)
				(type default)
			)
			(layer "F.SilkS")
		)
		(fp_line
			(start 2.1336 1.4224)
			(end 2.1336 -1.4224)
			(stroke
				(width 0.1524)
				(type default)
			)
			(layer "F.SilkS")
		)
		(fp_poly
			(pts
				(xy -2.2098 -1.4224) (xy -2.2098 1.4224) (xy 2.2098 1.4224) (xy 2.2098 -1.4224)
			)
			(stroke
				(width 0)
				(type default)
			)
			(fill yes)
			(layer "F.SilkS")
		)
		(fp_rect
			(start -2.450084 2.999994)
			(end 2.450084 -2.999994)
			(stroke
				(width 0)
				(type default)
			)
			(fill no)
			(layer "F.CrtYd")
		)
		(fp_poly
			(pts
				(xy -2.8194 3.6322) (xy -2.8194 -3.6322) (xy 2.8194 -3.6322) (xy 2.8194 1.18364) (xy 2.450084 1.18364)
				(xy 2.450084 -2.999994) (xy -2.450084 -2.999994) (xy -2.450084 2.999994) (xy 2.450084 2.999994)
				(xy 2.450084 1.18618) (xy 2.8194 1.18618) (xy 2.8194 3.6322)
			)
			(stroke
				(width 0)
				(type default)
			)
			(fill no)
			(layer "F.CrtYd")
		)
		(fp_rect
			(start -2.8194 3.6322)
			(end 2.8194 -3.6322)
			(stroke
				(width 0)
				(type default)
			)
			(fill no)
			(layer "F.Fab")
		)
		(pad "1" smd rect
			(at -1.905 2.54)
			(size 0.635 1.651)
			(layers "F.Cu" "F.Mask" "F.Paste")
			(net "P12V_B")
		)
		(pad "2" smd rect
			(at -0.635 2.54)
			(size 0.635 1.651)
			(layers "F.Cu" "F.Mask" "F.Paste")
			(net "P12V_B")
		)
		(pad "3" smd rect
			(at 0.635 2.54)
			(size 0.635 1.651)
			(layers "F.Cu" "F.Mask" "F.Paste")
			(net "P12V_B")
		)
		(pad "4" smd rect
			(at 1.905 2.54)
			(size 0.635 1.651)
			(layers "F.Cu" "F.Mask" "F.Paste")
			(net "SW_HDD_N11")
		)
		(pad "5" smd rect
			(at 1.905 -2.54)
			(size 0.635 1.651)
			(layers "F.Cu" "F.Mask" "F.Paste")
			(net "P12V_HDD11")
		)
		(pad "6" smd rect
			(at 0.635 -2.54)
			(size 0.635 1.651)
			(layers "F.Cu" "F.Mask" "F.Paste")
			(net "P12V_HDD11")
		)
		(pad "7" smd rect
			(at -0.635 -2.54)
			(size 0.635 1.651)
			(layers "F.Cu" "F.Mask" "F.Paste")
			(net "P12V_HDD11")
		)
		(pad "8" smd rect
			(at -1.905 -2.54)
			(size 0.635 1.651)
			(layers "F.Cu" "F.Mask" "F.Paste")
			(net "P12V_HDD11")
		)
	)
	(footprint ""
		(layer "F.Cu")
		(at 431.927 -248.793 90)
		(property "Reference" "D9"
			(at 0 0 90)
			(layer "F.SilkS")
			(hide yes)
			(effects
				(font
					(size 1.27 1.27)
				)
			)
		)
		(property "Value" "RB551V30-GP"
			(at 0 -6.7818 90)
			(unlocked yes)
			(layer "F.Fab")
			(hide yes)
			(effects
				(font
					(size 1.016 1.016)
					(thickness 0.1524)
				)
			)
		)
		(property "Device Type" "SOD323AKH38"
			(at 0 -8.6868 90)
			(unlocked yes)
			(layer "F.Fab")
			(hide yes)
			(effects
				(font
					(size 1.016 1.016)
					(thickness 0.1524)
				)
			)
		)
		(duplicate_pad_numbers_are_jumpers no)
		(fp_line
			(start 0.889 -1.9304)
			(end 0.889 2.159)
			(stroke
				(width 0.1524)
				(type default)
			)
			(layer "F.SilkS")
		)
		(fp_line
			(start -0.889 -1.9304)
			(end 0.889 -1.9304)
			(stroke
				(width 0.1524)
				(type default)
			)
			(layer "F.SilkS")
		)
		(fp_line
			(start 0.762 2.0574)
			(end -0.762 2.0574)
			(stroke
				(width 0.508)
				(type default)
			)
			(layer "F.SilkS")
		)
		(fp_line
			(start 0.889 2.159)
			(end -0.889 2.159)
			(stroke
				(width 0.1524)
				(type default)
			)
			(layer "F.SilkS")
		)
		(fp_line
			(start -0.889 2.159)
			(end -0.889 -1.9304)
			(stroke
				(width 0.1524)
				(type default)
			)
			(layer "F.SilkS")
		)
		(fp_rect
			(start -1.016 2.3114)
			(end 1.016 -2.0066)
			(stroke
				(width 0)
				(type default)
			)
			(fill no)
			(layer "F.CrtYd")
		)
		(fp_poly
			(pts
				(xy -1.016 -2.0066) (xy 1.016 -2.0066) (xy 1.016 2.3114) (xy -1.016 2.3114)
			)
			(stroke
				(width 0)
				(type default)
			)
			(fill no)
			(layer "F.Fab")
		)
		(pad "A" smd rect
			(at 0 -1.143 90)
			(size 0.5588 1.016)
			(layers "F.Cu" "F.Mask" "F.Paste")
			(net "SW_HDD_R9")
		)
		(pad "K" smd rect
			(at 0 1.143 90)
			(size 0.5588 1.016)
			(layers "F.Cu" "F.Mask" "F.Paste")
			(net "SW_HDD_N9")
		)
	)
	(footprint ""
		(layer "F.Cu")
		(at 22.9362 -133.4262 -90)
		(property "Reference" "R356"
			(at 0 0 270)
			(layer "F.SilkS")
			(hide yes)
			(effects
				(font
					(size 1.27 1.27)
				)
			)
		)
		(property "Value" "1KR2F-3-GP"
			(at 0.064008 -3.993896 270)
			(unlocked yes)
			(layer "F.Fab")
			(hide yes)
			(effects
				(font
					(size 1.016 1.016)
					(thickness 0.1524)
				)
			)
		)
		(property "Device Type" "R402H16"
			(at 0.064008 -5.517896 270)
			(unlocked yes)
			(layer "F.Fab")
			(hide yes)
			(effects
				(font
					(size 1.016 1.016)
					(thickness 0.1524)
				)
			)
		)
		(duplicate_pad_numbers_are_jumpers no)
		(fp_line
			(start -0.508 -0.9398)
			(end -0.508 0.9398)
			(stroke
				(width 0.1524)
				(type default)
			)
			(layer "F.SilkS")
		)
		(fp_line
			(start 0.508 -0.9398)
			(end -0.508 -0.9398)
			(stroke
				(width 0.1524)
				(type default)
			)
			(layer "F.SilkS")
		)
		(fp_rect
			(start -0.508 0.9398)
			(end 0.508 -0.9398)
			(stroke
				(width 0)
				(type default)
			)
			(fill no)
			(layer "F.CrtYd")
		)
		(fp_rect
			(start -0.508 0.9398)
			(end 0.508 -0.9398)
			(stroke
				(width 0)
				(type default)
			)
			(fill no)
			(layer "F.Fab")
		)
		(pad "1" smd custom
			(at 0 -0.4445 270)
			(size 0.1397 0.1397)
			(layers "F.Cu" "F.Mask" "F.Paste")
			(net "P3V3_STBY_B")
			(options
				(clearance outline)
				(anchor circle)
			)
			(primitives
				(gr_poly
					(pts
						(arc
							(start -0.1778 -0.2794)
							(mid -0.249642 -0.249642)
							(end -0.2794 -0.1778)
						)
						(arc
							(start -0.2794 0.1778)
							(mid -0.249642 0.249642)
							(end -0.1778 0.2794)
						)
						(arc
							(start 0.1778 0.2794)
							(mid 0.249642 0.249642)
							(end 0.2794 0.1778)
						)
						(arc
							(start 0.2794 -0.1778)
							(mid 0.249642 -0.249642)
							(end 0.1778 -0.2794)
						)
					)
					(width 0)
					(fill yes)
				)
			)
		)
		(pad "2" smd custom
			(at 0 0.4445 270)
			(size 0.1397 0.1397)
			(layers "F.Cu" "F.Mask" "F.Paste")
			(net "SW_PWR_R_HDD12")
			(options
				(clearance outline)
				(anchor circle)
			)
			(primitives
				(gr_poly
					(pts
						(arc
							(start -0.1778 -0.2794)
							(mid -0.249642 -0.249642)
							(end -0.2794 -0.1778)
						)
						(arc
							(start -0.2794 0.1778)
							(mid -0.249642 0.249642)
							(end -0.1778 0.2794)
						)
						(arc
							(start 0.1778 0.2794)
							(mid 0.249642 0.249642)
							(end 0.2794 0.1778)
						)
						(arc
							(start 0.2794 -0.1778)
							(mid 0.249642 -0.249642)
							(end 0.1778 -0.2794)
						)
					)
					(width 0)
					(fill yes)
				)
			)
		)
	)
	(footprint ""
		(layer "F.Cu")
		(at 48.26 -139.065 -90)
		(property "Reference" "C207"
			(at 0 0 270)
			(layer "F.SilkS")
			(hide yes)
			(effects
				(font
					(size 1.27 1.27)
				)
			)
		)
		(property "Value" "SCD033U25V2KX-GP"
			(at 1.1811 -2.7051 270)
			(unlocked yes)
			(layer "F.Fab")
			(hide yes)
			(effects
				(font
					(size 1.016 1.016)
					(thickness 0.1524)
				)
			)
		)
		(property "Device Type" "C402H22"
			(at 1.1811 -4.2291 270)
			(unlocked yes)
			(layer "F.Fab")
			(hide yes)
			(effects
				(font
					(size 1.016 1.016)
					(thickness 0.1524)
				)
			)
		)
		(duplicate_pad_numbers_are_jumpers no)
		(fp_rect
			(start -0.4318 0.9525)
			(end 0.4318 -0.9525)
			(stroke
				(width 0)
				(type default)
			)
			(fill no)
			(layer "F.CrtYd")
		)
		(fp_rect
			(start -0.4318 0.9525)
			(end 0.4318 -0.9525)
			(stroke
				(width 0)
				(type default)
			)
			(fill no)
			(layer "F.Fab")
		)
		(pad "1" smd custom
			(at 0 -0.4445 270)
			(size 0.1524 0.1524)
			(layers "F.Cu" "F.Mask" "F.Paste")
			(net "SW_HDD_P13")
			(options
				(clearance outline)
				(anchor circle)
			)
			(primitives
				(gr_poly
					(pts
						(arc
							(start 0.3048 -0.2032)
							(mid 0.275042 -0.275042)
							(end 0.2032 -0.3048)
						)
						(arc
							(start -0.2032 -0.3048)
							(mid -0.275042 -0.275042)
							(end -0.3048 -0.2032)
						)
						(arc
							(start -0.3048 0.2032)
							(mid -0.275042 0.275042)
							(end -0.2032 0.3048)
						)
						(arc
							(start 0.2032 0.3048)
							(mid 0.275042 0.275042)
							(end 0.3048 0.2032)
						)
					)
					(width 0)
					(fill yes)
				)
			)
		)
		(pad "2" smd custom
			(at 0 0.4445 270)
			(size 0.1524 0.1524)
			(layers "F.Cu" "F.Mask" "F.Paste")
			(net "GND")
			(options
				(clearance outline)
				(anchor circle)
			)
			(primitives
				(gr_poly
					(pts
						(arc
							(start 0.3048 -0.2032)
							(mid 0.275042 -0.275042)
							(end 0.2032 -0.3048)
						)
						(arc
							(start -0.2032 -0.3048)
							(mid -0.275042 -0.275042)
							(end -0.3048 -0.2032)
						)
						(arc
							(start -0.3048 0.2032)
							(mid -0.275042 0.275042)
							(end -0.2032 0.3048)
						)
						(arc
							(start 0.2032 0.3048)
							(mid 0.275042 0.275042)
							(end 0.3048 0.2032)
						)
					)
					(width 0)
					(fill yes)
				)
			)
		)
	)
	(footprint ""
		(layer "F.Cu")
		(at 184.277 -368.046 -90)
		(property "Reference" "R989"
			(at 0 0 270)
			(layer "F.SilkS")
			(hide yes)
			(effects
				(font
					(size 1.27 1.27)
				)
			)
		)
		(property "Value" "10KR2F-2-GP"
			(at 0.064008 -3.993896 270)
			(unlocked yes)
			(layer "F.Fab")
			(hide yes)
			(effects
				(font
					(size 1.016 1.016)
					(thickness 0.1524)
				)
			)
		)
		(property "Device Type" "R402H16"
			(at 0.064008 -5.517896 270)
			(unlocked yes)
			(layer "F.Fab")
			(hide yes)
			(effects
				(font
					(size 1.016 1.016)
					(thickness 0.1524)
				)
			)
		)
		(duplicate_pad_numbers_are_jumpers no)
		(fp_line
			(start -0.508 -0.9398)
			(end -0.508 0.9398)
			(stroke
				(width 0.1524)
				(type default)
			)
			(layer "F.SilkS")
		)
		(fp_line
			(start 0.508 -0.9398)
			(end -0.508 -0.9398)
			(stroke
				(width 0.1524)
				(type default)
			)
			(layer "F.SilkS")
		)
		(fp_rect
			(start -0.508 0.9398)
			(end 0.508 -0.9398)
			(stroke
				(width 0)
				(type default)
			)
			(fill no)
			(layer "F.CrtYd")
		)
		(fp_rect
			(start -0.508 0.9398)
			(end 0.508 -0.9398)
			(stroke
				(width 0)
				(type default)
			)
			(fill no)
			(layer "F.Fab")
		)
		(pad "1" smd custom
			(at 0 -0.4445 270)
			(size 0.1397 0.1397)
			(layers "F.Cu" "F.Mask" "F.Paste")
			(net "P12V_CLIP")
			(options
				(clearance outline)
				(anchor circle)
			)
			(primitives
				(gr_poly
					(pts
						(arc
							(start -0.1778 -0.2794)
							(mid -0.249642 -0.249642)
							(end -0.2794 -0.1778)
						)
						(arc
							(start -0.2794 0.1778)
							(mid -0.249642 0.249642)
							(end -0.1778 0.2794)
						)
						(arc
							(start 0.1778 0.2794)
							(mid 0.249642 0.249642)
							(end 0.2794 0.1778)
						)
						(arc
							(start 0.2794 -0.1778)
							(mid 0.249642 -0.249642)
							(end 0.1778 -0.2794)
						)
					)
					(width 0)
					(fill yes)
				)
			)
		)
		(pad "2" smd custom
			(at 0 0.4445 270)
			(size 0.1397 0.1397)
			(layers "F.Cu" "F.Mask" "F.Paste")
			(net "12V_HS_ENABLE")
			(options
				(clearance outline)
				(anchor circle)
			)
			(primitives
				(gr_poly
					(pts
						(arc
							(start -0.1778 -0.2794)
							(mid -0.249642 -0.249642)
							(end -0.2794 -0.1778)
						)
						(arc
							(start -0.2794 0.1778)
							(mid -0.249642 0.249642)
							(end -0.1778 0.2794)
						)
						(arc
							(start 0.1778 0.2794)
							(mid 0.249642 0.249642)
							(end 0.2794 0.1778)
						)
						(arc
							(start 0.2794 -0.1778)
							(mid 0.249642 -0.249642)
							(end 0.1778 -0.2794)
						)
					)
					(width 0)
					(fill yes)
				)
			)
		)
	)
)
